(kicad_pcb
	(version 20260206)
	(generator "pcbnew")
	(generator_version "10.0")
	(general
		(thickness 1.6)
		(legacy_teardrops no)
	)
	(paper "A4")
	(title_block
		(title "v1-chassis-manager — T6M_CM_d_v01_1031_1645.brd")
		(comment 1 "Open CloudServer (Microsoft) / footprints 904-912 of 2512")
	)
	(layers
		(0 "F.Cu" signal "TOP")
		(4 "In1.Cu" signal "GND1")
		(6 "In2.Cu" signal "IN1")
		(8 "In3.Cu" signal "VCC1")
		(10 "In4.Cu" signal "VCC2")
		(12 "In5.Cu" signal "GND2")
		(14 "In6.Cu" signal "IN2")
		(16 "In7.Cu" signal "IN3")
		(18 "In8.Cu" signal "GND3")
		(2 "B.Cu" signal "BOTTOM")
		(9 "F.Adhes" user "F.Adhesive")
		(11 "B.Adhes" user "B.Adhesive")
		(13 "F.Paste" user "Package Geometry/Pastemask Top")
		(15 "B.Paste" user "Package Geometry/Pastemask Bottom")
		(5 "F.SilkS" user "Ref Des/Silkscreen Top")
		(7 "B.SilkS" user "Ref Des/Silkscreen Bottom")
		(1 "F.Mask" user "Board Geometry/Soldermask Top")
		(3 "B.Mask" user "Board Geometry/Soldermask Bottom")
		(17 "Dwgs.User" user "User.Drawings")
		(19 "Cmts.User" user "User.Comments")
		(21 "Eco1.User" user "User.Eco1")
		(23 "Eco2.User" user "User.Eco2")
		(25 "Edge.Cuts" user "Board Geometry/Outline")
		(27 "Margin" user)
		(31 "F.CrtYd" user "Package Geometry/Place Bound Top")
		(29 "B.CrtYd" user "Package Geometry/Place Bound Bottom")
		(35 "F.Fab" user "Ref Des/Assembly Top")
		(33 "B.Fab" user "Ref Des/Assembly Bottom")
	)
	(footprint ""
		(layer "F.Cu")
		(at 79.39786 -92.076524)
		(property "Reference" "R142"
			(at -0.62992 18.989294 0)
			(unlocked yes)
			(layer "F.SilkS")
			(effects
				(font
					(size 0.7874 0.5842)
					(thickness 0.1524)
				)
				(justify left)
			)
		)
		(property "Value" ""
			(at 0 0 0)
			(layer "F.Fab")
			(effects
				(font
					(size 1.27 1.27)
				)
			)
		)
		(duplicate_pad_numbers_are_jumpers no)
		(fp_line
			(start -0.7874 -0.4064)
			(end 0.7874 -0.4064)
			(stroke
				(width 0.1524)
				(type default)
			)
			(layer "F.SilkS")
		)
		(fp_line
			(start -0.7874 0.4064)
			(end -0.7874 -0.4064)
			(stroke
				(width 0.1524)
				(type default)
			)
			(layer "F.SilkS")
		)
		(fp_line
			(start 0.7874 -0.4064)
			(end 0.7874 0.4064)
			(stroke
				(width 0.1524)
				(type default)
			)
			(layer "F.SilkS")
		)
		(fp_line
			(start 0.7874 0.4064)
			(end -0.7874 0.4064)
			(stroke
				(width 0.1524)
				(type default)
			)
			(layer "F.SilkS")
		)
		(fp_poly
			(pts
				(xy -0.508 0.2794) (xy -0.508 0.2286) (xy -0.635 0.2286) (xy -0.635 -0.254) (xy -0.5334 -0.254)
				(xy -0.5334 -0.2794) (xy 0.5334 -0.2794) (xy 0.5334 -0.254) (xy 0.635 -0.254) (xy 0.635 0.254) (xy 0.5334 0.254)
				(xy 0.5334 0.2794)
			)
			(stroke
				(width 0)
				(type default)
			)
			(fill no)
			(layer "F.CrtYd")
		)
		(pad "1" smd rect
			(at 0.40005 0)
			(size 0.4572 0.508)
			(layers "F.Cu" "F.Mask" "F.Paste")
			(net "GND")
		)
		(pad "2" smd rect
			(at -0.40005 0)
			(size 0.4572 0.508)
			(layers "F.Cu" "F.Mask" "F.Paste")
			(net "FM_CPLD_NODE1_SYS_PG")
		)
	)
	(footprint ""
		(layer "F.Cu")
		(at 111.87176 -172.625512 180)
		(property "Reference" "R663"
			(at 2.0701 10.374376 0)
			(unlocked yes)
			(layer "F.SilkS")
			(effects
				(font
					(size 0.7874 0.5842)
					(thickness 0.1524)
				)
				(justify left)
			)
		)
		(property "Value" ""
			(at 0 0 180)
			(layer "F.Fab")
			(effects
				(font
					(size 1.27 1.27)
				)
			)
		)
		(duplicate_pad_numbers_are_jumpers no)
		(fp_line
			(start 0.7874 0.4064)
			(end -0.7874 0.4064)
			(stroke
				(width 0.1524)
				(type default)
			)
			(layer "F.SilkS")
		)
		(fp_line
			(start 0.7874 -0.4064)
			(end 0.7874 0.4064)
			(stroke
				(width 0.1524)
				(type default)
			)
			(layer "F.SilkS")
		)
		(fp_line
			(start -0.7874 0.4064)
			(end -0.7874 -0.4064)
			(stroke
				(width 0.1524)
				(type default)
			)
			(layer "F.SilkS")
		)
		(fp_line
			(start -0.7874 -0.4064)
			(end 0.7874 -0.4064)
			(stroke
				(width 0.1524)
				(type default)
			)
			(layer "F.SilkS")
		)
		(fp_poly
			(pts
				(xy -0.508 0.2794) (xy -0.508 0.2286) (xy -0.635 0.2286) (xy -0.635 -0.254) (xy -0.5334 -0.254)
				(xy -0.5334 -0.2794) (xy 0.5334 -0.2794) (xy 0.5334 -0.254) (xy 0.635 -0.254) (xy 0.635 0.254) (xy 0.5334 0.254)
				(xy 0.5334 0.2794)
			)
			(stroke
				(width 0)
				(type default)
			)
			(fill no)
			(layer "F.CrtYd")
		)
		(pad "1" smd rect
			(at 0.40005 0 180)
			(size 0.4572 0.508)
			(layers "F.Cu" "F.Mask" "F.Paste")
			(net "P3V3_NODE1")
		)
		(pad "2" smd rect
			(at -0.40005 0 180)
			(size 0.4572 0.508)
			(layers "F.Cu" "F.Mask" "F.Paste")
			(net "I2C_COM3_SCL")
		)
	)
	(footprint ""
		(layer "F.Cu")
		(at 42.169588 -109.860334)
		(property "Reference" "PC19"
			(at -1.389634 -4.695444 0)
			(unlocked yes)
			(layer "F.SilkS")
			(effects
				(font
					(size 0.7874 0.5842)
					(thickness 0.1524)
				)
				(justify left)
			)
		)
		(property "Value" ""
			(at 0 0 0)
			(layer "F.Fab")
			(effects
				(font
					(size 1.27 1.27)
				)
			)
		)
		(duplicate_pad_numbers_are_jumpers no)
		(fp_line
			(start -0.7874 -0.4064)
			(end 0.7874 -0.4064)
			(stroke
				(width 0.1524)
				(type default)
			)
			(layer "F.SilkS")
		)
		(fp_line
			(start -0.7874 0.4064)
			(end -0.7874 -0.4064)
			(stroke
				(width 0.1524)
				(type default)
			)
			(layer "F.SilkS")
		)
		(fp_line
			(start 0 0.381)
			(end 0 -0.381)
			(stroke
				(width 0.1524)
				(type default)
			)
			(layer "F.SilkS")
		)
		(fp_line
			(start 0.7874 -0.4064)
			(end 0.7874 0.4064)
			(stroke
				(width 0.1524)
				(type default)
			)
			(layer "F.SilkS")
		)
		(fp_line
			(start 0.7874 0.4064)
			(end -0.7874 0.4064)
			(stroke
				(width 0.1524)
				(type default)
			)
			(layer "F.SilkS")
		)
		(fp_poly
			(pts
				(xy -0.5334 0.254) (xy -0.635 0.254) (xy -0.635 0.2286) (xy -0.635 -0.254) (xy -0.5334 -0.254) (xy -0.5334 -0.2794)
				(xy 0.5334 -0.2794) (xy 0.5334 -0.254) (xy 0.635 -0.254) (xy 0.635 0.254) (xy 0.5334 0.254) (xy 0.5334 0.2794)
				(xy -0.508 0.2794) (xy -0.5334 0.2794)
			)
			(stroke
				(width 0)
				(type default)
			)
			(fill no)
			(layer "F.CrtYd")
		)
		(pad "1" smd rect
			(at 0.40005 0)
			(size 0.4572 0.508)
			(layers "F.Cu" "F.Mask" "F.Paste")
			(net "P3V3_STB_NODE1_VREG5")
		)
		(pad "2" smd rect
			(at -0.40005 0)
			(size 0.4572 0.508)
			(layers "F.Cu" "F.Mask" "F.Paste")
			(net "GND")
		)
	)
	(footprint ""
		(layer "F.Cu")
		(at 20.79752 -36.390326)
		(property "Reference" "J34"
			(at -0.05842 2.632202 0)
			(unlocked yes)
			(layer "F.SilkS")
			(effects
				(font
					(size 0.7874 0.5842)
					(thickness 0.1524)
				)
				(justify left)
			)
		)
		(property "Value" ""
			(at 0 0 0)
			(layer "F.Fab")
			(effects
				(font
					(size 1.27 1.27)
				)
			)
		)
		(duplicate_pad_numbers_are_jumpers no)
		(fp_line
			(start -2.739898 -1.27)
			(end -2.739898 1.27)
			(stroke
				(width 0.1524)
				(type default)
			)
			(layer "F.SilkS")
		)
		(fp_line
			(start -2.739898 1.27)
			(end -2.690114 1.27)
			(stroke
				(width 0.1524)
				(type default)
			)
			(layer "F.SilkS")
		)
		(fp_line
			(start -2.739898 1.27)
			(end 2.739898 1.27)
			(stroke
				(width 0.1524)
				(type default)
			)
			(layer "F.SilkS")
		)
		(fp_line
			(start 2.739898 -1.27)
			(end -2.739898 -1.27)
			(stroke
				(width 0.1524)
				(type default)
			)
			(layer "F.SilkS")
		)
		(fp_line
			(start 2.739898 1.27)
			(end 2.739898 -1.27)
			(stroke
				(width 0.1524)
				(type default)
			)
			(layer "F.SilkS")
		)
		(fp_poly
			(pts
				(xy -1.2192 1.7653) (xy -1.9558 3.5687) (xy -0.5842 3.5687)
			)
			(stroke
				(width 0)
				(type default)
			)
			(fill yes)
			(layer "F.SilkS")
		)
		(fp_rect
			(start -2.1844 0.9144)
			(end 2.1844 -0.9144)
			(stroke
				(width 0)
				(type default)
			)
			(fill no)
			(layer "B.CrtYd")
		)
		(fp_poly
			(pts
				(xy -2.739898 1.27) (xy 2.739898 1.27) (xy 2.739898 -1.27) (xy -2.739898 -1.27)
			)
			(stroke
				(width 0)
				(type default)
			)
			(fill no)
			(layer "F.CrtYd")
		)
		(fp_line
			(start -2.739898 -1.27)
			(end -2.739898 1.27)
			(stroke
				(width 0.1)
				(type default)
			)
			(layer "F.Fab")
		)
		(fp_line
			(start -2.739898 1.27)
			(end -2.690114 1.27)
			(stroke
				(width 0.1)
				(type default)
			)
			(layer "F.Fab")
		)
		(fp_line
			(start -2.739898 1.27)
			(end 2.739898 1.27)
			(stroke
				(width 0.1)
				(type default)
			)
			(layer "F.Fab")
		)
		(fp_line
			(start 2.739898 -1.27)
			(end -2.739898 -1.27)
			(stroke
				(width 0.1)
				(type default)
			)
			(layer "F.Fab")
		)
		(fp_line
			(start 2.739898 1.27)
			(end 2.739898 -1.27)
			(stroke
				(width 0.1)
				(type default)
			)
			(layer "F.Fab")
		)
		(fp_poly
			(pts
				(xy -1.2192 1.7653) (xy -1.9558 3.5687) (xy -0.5842 3.5687)
			)
			(stroke
				(width 0)
				(type default)
			)
			(fill yes)
			(layer "F.Fab")
		)
		(fp_text user "1"
			(at -2.49174 2.146046 0)
			(unlocked yes)
			(layer "F.SilkS")
			(effects
				(font
					(size 0.7874 0.5842)
					(thickness 0.1524)
				)
				(justify left)
			)
		)
		(fp_text user "2"
			(at 3.09118 -0.73279 0)
			(unlocked yes)
			(layer "F.SilkS")
			(effects
				(font
					(size 0.7874 0.5842)
					(thickness 0.1524)
				)
				(justify left)
			)
		)
		(fp_text user "1"
			(at -0.97536 -1.573784 0)
			(unlocked yes)
			(layer "B.SilkS")
			(effects
				(font
					(size 0.7874 0.5842)
					(thickness 0.1524)
				)
				(justify left mirror)
			)
		)
		(fp_text user "2"
			(at 1.59512 -1.492504 0)
			(unlocked yes)
			(layer "B.SilkS")
			(effects
				(font
					(size 0.7874 0.5842)
					(thickness 0.1524)
				)
				(justify left mirror)
			)
		)
		(fp_text user "1"
			(at -1.9431 -0.18669 0)
			(unlocked yes)
			(layer "B.Fab")
			(effects
				(font
					(size 1.6002 1.1938)
					(thickness 0.000001)
				)
				(justify left mirror)
			)
		)
		(fp_text user "2"
			(at 3.1369 -0.18669 0)
			(unlocked yes)
			(layer "B.Fab")
			(effects
				(font
					(size 1.6002 1.1938)
					(thickness 0.000001)
				)
				(justify left mirror)
			)
		)
		(fp_text user "1"
			(at -2.8829 2.48031 0)
			(unlocked yes)
			(layer "F.Fab")
			(effects
				(font
					(size 1.6002 1.1938)
					(thickness 0.000001)
				)
				(justify left)
			)
		)
		(fp_text user "2"
			(at 0.6731 2.48031 0)
			(unlocked yes)
			(layer "F.Fab")
			(effects
				(font
					(size 1.6002 1.1938)
					(thickness 0.000001)
				)
				(justify left)
			)
		)
		(pad "1" thru_hole rect
			(at -1.27 0)
			(size 1.7272 1.7272)
			(drill 1.2192)
			(layers "*.Cu" "*.Mask")
			(remove_unused_layers no)
			(net "CONSOLE_SELECT_N")
			(clearance 0)
			(padstack
				(mode front_inner_back)
				(layer "Inner"
					(shape circle)
					(size 1.7272 1.7272)
					(clearance 0)
				)
				(layer "B.Cu"
					(shape rect)
					(size 1.7272 1.7272)
					(clearance 0)
				)
			)
		)
		(pad "2" thru_hole circle
			(at 1.27 0)
			(size 1.7272 1.7272)
			(drill 1.2192)
			(layers "*.Cu" "*.Mask")
			(remove_unused_layers no)
			(net "GND")
			(clearance 0)
		)
	)
	(footprint ""
		(layer "F.Cu")
		(at 79.366364 -17.679416 90)
		(property "Reference" "C149"
			(at -4.546854 5.52323 90)
			(unlocked yes)
			(layer "F.SilkS")
			(effects
				(font
					(size 0.7874 0.5842)
					(thickness 0.1524)
				)
				(justify left)
			)
		)
		(property "Value" ""
			(at 0 0 90)
			(layer "F.Fab")
			(effects
				(font
					(size 1.27 1.27)
				)
			)
		)
		(duplicate_pad_numbers_are_jumpers no)
		(fp_line
			(start 0.7874 -0.4064)
			(end 0.7874 0.4064)
			(stroke
				(width 0.1524)
				(type default)
			)
			(layer "F.SilkS")
		)
		(fp_line
			(start -0.7874 -0.4064)
			(end 0.7874 -0.4064)
			(stroke
				(width 0.1524)
				(type default)
			)
			(layer "F.SilkS")
		)
		(fp_line
			(start 0 0.381)
			(end 0 -0.381)
			(stroke
				(width 0.1524)
				(type default)
			)
			(layer "F.SilkS")
		)
		(fp_line
			(start 0.7874 0.4064)
			(end -0.7874 0.4064)
			(stroke
				(width 0.1524)
				(type default)
			)
			(layer "F.SilkS")
		)
		(fp_line
			(start -0.7874 0.4064)
			(end -0.7874 -0.4064)
			(stroke
				(width 0.1524)
				(type default)
			)
			(layer "F.SilkS")
		)
		(fp_poly
			(pts
				(xy -0.5334 0.254) (xy -0.635 0.254) (xy -0.635 0.2286) (xy -0.635 -0.254) (xy -0.5334 -0.254) (xy -0.5334 -0.2794)
				(xy 0.5334 -0.2794) (xy 0.5334 -0.254) (xy 0.635 -0.254) (xy 0.635 0.254) (xy 0.5334 0.254) (xy 0.5334 0.2794)
				(xy -0.508 0.2794) (xy -0.5334 0.2794)
			)
			(stroke
				(width 0)
				(type default)
			)
			(fill no)
			(layer "F.CrtYd")
		)
		(pad "1" smd rect
			(at 0.40005 0 90)
			(size 0.4572 0.508)
			(layers "F.Cu" "F.Mask" "F.Paste")
			(net "PV_VDDR_NODE1")
		)
		(pad "2" smd rect
			(at -0.40005 0 90)
			(size 0.4572 0.508)
			(layers "F.Cu" "F.Mask" "F.Paste")
			(net "GND")
		)
	)
	(footprint ""
		(layer "F.Cu")
		(at 142.73276 -115.863624 180)
		(property "Reference" "R13"
			(at -1.512824 0.105918 0)
			(unlocked yes)
			(layer "F.SilkS")
			(effects
				(font
					(size 0.7874 0.5842)
					(thickness 0.1524)
				)
				(justify left)
			)
		)
		(property "Value" ""
			(at 0 0 180)
			(layer "F.Fab")
			(effects
				(font
					(size 1.27 1.27)
				)
			)
		)
		(duplicate_pad_numbers_are_jumpers no)
		(fp_line
			(start 0.7874 0.4064)
			(end -0.7874 0.4064)
			(stroke
				(width 0.1524)
				(type default)
			)
			(layer "F.SilkS")
		)
		(fp_line
			(start 0.7874 -0.4064)
			(end 0.7874 0.4064)
			(stroke
				(width 0.1524)
				(type default)
			)
			(layer "F.SilkS")
		)
		(fp_line
			(start -0.7874 0.4064)
			(end -0.7874 -0.4064)
			(stroke
				(width 0.1524)
				(type default)
			)
			(layer "F.SilkS")
		)
		(fp_line
			(start -0.7874 -0.4064)
			(end 0.7874 -0.4064)
			(stroke
				(width 0.1524)
				(type default)
			)
			(layer "F.SilkS")
		)
		(fp_poly
			(pts
				(xy -0.508 0.2794) (xy -0.508 0.2286) (xy -0.635 0.2286) (xy -0.635 -0.254) (xy -0.5334 -0.254)
				(xy -0.5334 -0.2794) (xy 0.5334 -0.2794) (xy 0.5334 -0.254) (xy 0.635 -0.254) (xy 0.635 0.254) (xy 0.5334 0.254)
				(xy 0.5334 0.2794)
			)
			(stroke
				(width 0)
				(type default)
			)
			(fill no)
			(layer "F.CrtYd")
		)
		(pad "1" smd rect
			(at 0.40005 0 180)
			(size 0.4572 0.508)
			(layers "F.Cu" "F.Mask" "F.Paste")
			(net "CLKREQB_NODE1_N")
		)
		(pad "2" smd rect
			(at -0.40005 0 180)
			(size 0.4572 0.508)
			(layers "F.Cu" "F.Mask" "F.Paste")
			(net "P3V3_CLK_NODE1")
		)
	)
	(footprint ""
		(layer "F.Cu")
		(at 191.369442 -114.562128 180)
		(property "Reference" "R1028"
			(at -1.483614 -0.118364 0)
			(unlocked yes)
			(layer "F.SilkS")
			(effects
				(font
					(size 0.7874 0.5842)
					(thickness 0.1524)
				)
				(justify left)
			)
		)
		(property "Value" ""
			(at 0 0 180)
			(layer "F.Fab")
			(effects
				(font
					(size 1.27 1.27)
				)
			)
		)
		(duplicate_pad_numbers_are_jumpers no)
		(fp_line
			(start 0.7874 0.4064)
			(end -0.7874 0.4064)
			(stroke
				(width 0.1524)
				(type default)
			)
			(layer "F.SilkS")
		)
		(fp_line
			(start 0.7874 -0.4064)
			(end 0.7874 0.4064)
			(stroke
				(width 0.1524)
				(type default)
			)
			(layer "F.SilkS")
		)
		(fp_line
			(start -0.7874 0.4064)
			(end -0.7874 -0.4064)
			(stroke
				(width 0.1524)
				(type default)
			)
			(layer "F.SilkS")
		)
		(fp_line
			(start -0.7874 -0.4064)
			(end 0.7874 -0.4064)
			(stroke
				(width 0.1524)
				(type default)
			)
			(layer "F.SilkS")
		)
		(fp_poly
			(pts
				(xy -0.508 0.2794) (xy -0.508 0.2286) (xy -0.635 0.2286) (xy -0.635 -0.254) (xy -0.5334 -0.254)
				(xy -0.5334 -0.2794) (xy 0.5334 -0.2794) (xy 0.5334 -0.254) (xy 0.635 -0.254) (xy 0.635 0.254) (xy 0.5334 0.254)
				(xy 0.5334 0.2794)
			)
			(stroke
				(width 0)
				(type default)
			)
			(fill no)
			(layer "F.CrtYd")
		)
		(pad "1" smd rect
			(at 0.40005 0 180)
			(size 0.4572 0.508)
			(layers "F.Cu" "F.Mask" "F.Paste")
			(net "P12V_NODE1_PWRGD_EN")
		)
		(pad "2" smd rect
			(at -0.40005 0 180)
			(size 0.4572 0.508)
			(layers "F.Cu" "F.Mask" "F.Paste")
			(net "GND")
		)
	)
	(footprint ""
		(layer "F.Cu")
		(at 95.047562 -123.558046 -90)
		(property "Reference" "C1119"
			(at -0.09144 -0.626364 0)
			(unlocked yes)
			(layer "F.SilkS")
			(effects
				(font
					(size 0.7874 0.5842)
					(thickness 0.1524)
				)
				(justify left)
			)
		)
		(property "Value" ""
			(at 0 0 270)
			(layer "F.Fab")
			(effects
				(font
					(size 1.27 1.27)
				)
			)
		)
		(duplicate_pad_numbers_are_jumpers no)
		(fp_line
			(start -0.7874 0.4064)
			(end -0.7874 -0.4064)
			(stroke
				(width 0.1524)
				(type default)
			)
			(layer "F.SilkS")
		)
		(fp_line
			(start 0.7874 0.4064)
			(end -0.7874 0.4064)
			(stroke
				(width 0.1524)
				(type default)
			)
			(layer "F.SilkS")
		)
		(fp_line
			(start 0 0.381)
			(end 0 -0.381)
			(stroke
				(width 0.1524)
				(type default)
			)
			(layer "F.SilkS")
		)
		(fp_line
			(start -0.7874 -0.4064)
			(end 0.7874 -0.4064)
			(stroke
				(width 0.1524)
				(type default)
			)
			(layer "F.SilkS")
		)
		(fp_line
			(start 0.7874 -0.4064)
			(end 0.7874 0.4064)
			(stroke
				(width 0.1524)
				(type default)
			)
			(layer "F.SilkS")
		)
		(fp_poly
			(pts
				(xy -0.5334 0.254) (xy -0.635 0.254) (xy -0.635 0.2286) (xy -0.635 -0.254) (xy -0.5334 -0.254) (xy -0.5334 -0.2794)
				(xy 0.5334 -0.2794) (xy 0.5334 -0.254) (xy 0.635 -0.254) (xy 0.635 0.254) (xy 0.5334 0.254) (xy 0.5334 0.2794)
				(xy -0.508 0.2794) (xy -0.5334 0.2794)
			)
			(stroke
				(width 0)
				(type default)
			)
			(fill no)
			(layer "F.CrtYd")
		)
		(pad "1" smd rect
			(at 0.40005 0 270)
			(size 0.4572 0.508)
			(layers "F.Cu" "F.Mask" "F.Paste")
			(net "GND")
		)
		(pad "2" smd rect
			(at -0.40005 0 270)
			(size 0.4572 0.508)
			(layers "F.Cu" "F.Mask" "F.Paste")
			(net "P3V3_NODE1")
		)
	)
	(footprint ""
		(layer "F.Cu")
		(at 85.96376 -188.126624 90)
		(property "Reference" "C717"
			(at 4.548886 -1.831848 90)
			(unlocked yes)
			(layer "F.SilkS")
			(effects
				(font
					(size 0.7874 0.5842)
					(thickness 0.1524)
				)
				(justify left)
			)
		)
		(property "Value" ""
			(at 0 0 90)
			(layer "F.Fab")
			(effects
				(font
					(size 1.27 1.27)
				)
			)
		)
		(duplicate_pad_numbers_are_jumpers no)
		(fp_line
			(start 0.7874 -0.4064)
			(end 0.7874 0.4064)
			(stroke
				(width 0.1524)
				(type default)
			)
			(layer "F.SilkS")
		)
		(fp_line
			(start -0.7874 -0.4064)
			(end 0.7874 -0.4064)
			(stroke
				(width 0.1524)
				(type default)
			)
			(layer "F.SilkS")
		)
		(fp_line
			(start 0 0.381)
			(end 0 -0.381)
			(stroke
				(width 0.1524)
				(type default)
			)
			(layer "F.SilkS")
		)
		(fp_line
			(start 0.7874 0.4064)
			(end -0.7874 0.4064)
			(stroke
				(width 0.1524)
				(type default)
			)
			(layer "F.SilkS")
		)
		(fp_line
			(start -0.7874 0.4064)
			(end -0.7874 -0.4064)
			(stroke
				(width 0.1524)
				(type default)
			)
			(layer "F.SilkS")
		)
		(fp_poly
			(pts
				(xy -0.5334 0.254) (xy -0.635 0.254) (xy -0.635 0.2286) (xy -0.635 -0.254) (xy -0.5334 -0.254) (xy -0.5334 -0.2794)
				(xy 0.5334 -0.2794) (xy 0.5334 -0.254) (xy 0.635 -0.254) (xy 0.635 0.254) (xy 0.5334 0.254) (xy 0.5334 0.2794)
				(xy -0.508 0.2794) (xy -0.5334 0.2794)
			)
			(stroke
				(width 0)
				(type default)
			)
			(fill no)
			(layer "F.CrtYd")
		)
		(pad "1" smd rect
			(at 0.40005 0 90)
			(size 0.4572 0.508)
			(layers "F.Cu" "F.Mask" "F.Paste")
			(net "UART_T6_NODE4_TXD_R")
		)
		(pad "2" smd rect
			(at -0.40005 0 90)
			(size 0.4572 0.508)
			(layers "F.Cu" "F.Mask" "F.Paste")
			(net "GND")
		)
	)
)
